# SCM (Grand Teton) — schematic netlist excerpt (pin names and nets, part order shuffled) for the footprints in the layout excerpt that follows; sources: Cadence DE-HDL packaged netlist, KiCad conversion of 12092022_DA0F0TMDCD0_F0T_Management_Board_D_brd_V3_OCP.brd

J27  PICOPROBE_BXA  DELTA-L 4.0 EMPTY  pkg TRIANG_LAUNCH_3PXB  page 58
  \1_p\  = 85_10INCH_BOT_DN
  \2_n\  = 85_10INCH_BOT_DP
  \3_g\  = GND_P1

(kicad_pcb
	(version 20260206)
	(generator "pcbnew")
	(generator_version "10.0")
	(general
		(thickness 1.6)
		(legacy_teardrops no)
	)
	(paper "A4")
	(title_block
		(title "12092022_DA0F0TMDCD0_F0T_Management_Board_D_brd_V3_OCP.brd")
		(comment 1 "Grand Teton / footprints 1302-1302 of 1440")
	)
	(layers
		(0 "F.Cu" signal "TOP")
		(4 "In1.Cu" signal "GND")
		(6 "In2.Cu" signal "IN1")
		(8 "In3.Cu" signal "GND1")
		(10 "In4.Cu" signal "IN2")
		(12 "In5.Cu" signal "VCC")
		(14 "In6.Cu" signal "VCC1")
		(16 "In7.Cu" signal "IN3")
		(18 "In8.Cu" signal "GND2")
		(20 "In9.Cu" signal "IN4")
		(22 "In10.Cu" signal "GND3")
		(2 "B.Cu" signal "BOTTOM")
		(9 "F.Adhes" user "F.Adhesive")
		(11 "B.Adhes" user "B.Adhesive")
		(13 "F.Paste" user "Package Geometry/Pastemask Top")
		(15 "B.Paste" user "Package Geometry/Pastemask Bottom")
		(5 "F.SilkS" user "Ref Des/Silkscreen Top")
		(7 "B.SilkS" user "Ref Des/Silkscreen Bottom")
		(1 "F.Mask" user "Board Geometry/Soldermask Top")
		(3 "B.Mask" user "Board Geometry/Soldermask Bottom")
		(17 "Dwgs.User" user "User.Drawings")
		(19 "Cmts.User" user "User.Comments")
		(21 "Eco1.User" user "User.Eco1")
		(23 "Eco2.User" user "User.Eco2")
		(25 "Edge.Cuts" user "Board Geometry/Outline")
		(27 "Margin" user)
		(31 "F.CrtYd" user "Package Geometry/Place Bound Top")
		(29 "B.CrtYd" user "Package Geometry/Place Bound Bottom")
		(35 "F.Fab" user "Ref Des/Assembly Top")
		(33 "B.Fab" user "Ref Des/Assembly Bottom")
	)
	(footprint ""
		(layer "B.Cu")
		(at 101.2825 18.001488 -90)
		(property "Reference" "J27"
			(at 1.048512 2.88417 270)
			(unlocked yes)
			(layer "B.SilkS")
			(effects
				(font
					(size 0.7874 0.5842)
					(thickness 0.1524)
				)
				(justify left mirror)
			)
		)
		(property "Value" ""
			(at 0 0 90)
			(layer "B.Fab")
			(effects
				(font
					(size 1.27 1.27)
				)
				(justify mirror)
			)
		)
		(duplicate_pad_numbers_are_jumpers no)
		(fp_line
			(start -1.2192 2.1082)
			(end 1.2192 2.1082)
			(stroke
				(width 0.1524)
				(type default)
			)
			(layer "B.SilkS")
		)
		(fp_line
			(start 1.2192 2.1082)
			(end 1.2192 -2.1082)
			(stroke
				(width 0.1524)
				(type default)
			)
			(layer "B.SilkS")
		)
		(fp_line
			(start -1.2192 0.465582)
			(end -1.2192 2.1082)
			(stroke
				(width 0.1524)
				(type default)
			)
			(layer "B.SilkS")
		)
		(fp_line
			(start -1.2192 -2.1082)
			(end -1.2192 -0.45085)
			(stroke
				(width 0.1524)
				(type default)
			)
			(layer "B.SilkS")
		)
		(fp_line
			(start 1.2192 -2.1082)
			(end -1.2192 -2.1082)
			(stroke
				(width 0.1524)
				(type default)
			)
			(layer "B.SilkS")
		)
		(pad "" np_thru_hole circle
			(at -3.4671 -1.27 180)
			(size 1.0414 1.0414)
			(drill 1.0414)
			(layers "*.Cu" "*.Mask")
			(clearance 0.381)
			(thermal_gap 0.381)
		)
		(pad "" np_thru_hole circle
			(at -3.4671 1.27 180)
			(size 1.0414 1.0414)
			(drill 1.0414)
			(layers "*.Cu" "*.Mask")
			(clearance 0.381)
			(thermal_gap 0.381)
		)
		(pad "" np_thru_hole circle
			(at 2.8829 -1.27 180)
			(size 1.0414 1.0414)
			(drill 1.0414)
			(layers "*.Cu" "*.Mask")
			(clearance 0.381)
			(thermal_gap 0.381)
		)
		(pad "" np_thru_hole circle
			(at 2.8829 1.27 180)
			(size 1.0414 1.0414)
			(drill 1.0414)
			(layers "*.Cu" "*.Mask")
			(clearance 0.381)
			(thermal_gap 0.381)
		)
		(pad "1" smd rect
			(at -0.8255 -0.249936 180)
			(size 0.3048 0.508)
			(layers "B.Cu" "B.Mask" "B.Paste")
			(net "85_10INCH_BOT_DN")
		)
		(pad "2" smd rect
			(at -0.8255 0.249936 180)
			(size 0.3048 0.508)
			(layers "B.Cu" "B.Mask" "B.Paste")
			(net "85_10INCH_BOT_DP")
		)
		(pad "3" smd circle
			(at 0 0 90)
			(size 0 0)
			(layers "B.Cu" "B.Mask" "B.Paste")
			(net "GND_P1")
		)
		(zone
			(layers "F.Cu" "B.Cu" "In1.Cu" "In2.Cu" "In3.Cu" "In4.Cu" "In5.Cu" "In6.Cu"
				"In7.Cu" "In8.Cu" "In9.Cu" "In10.Cu"
			)
			(hatch none 0.5)
			(connect_pads
				(clearance 0)
			)
			(min_thickness 0.25)
			(keepout
				(tracks not_allowed)
				(vias allowed)
				(pads allowed)
				(copperpour not_allowed)
				(footprints allowed)
			)
			(placement
				(enabled no)
				(sheetname "")
			)
			(fill
				(thermal_gap 0.5)
				(thermal_bridge_width 0.5)
				(island_removal_mode 0)
			)
			(polygon
				(pts
					(arc
						(start 100.9396 14.534388)
						(mid 99.0854 14.534388)
						(end 100.9396 14.534388)
					)
				)
			)
		)
		(zone
			(layers "F.Cu" "B.Cu" "In1.Cu" "In2.Cu" "In3.Cu" "In4.Cu" "In5.Cu" "In6.Cu"
				"In7.Cu" "In8.Cu" "In9.Cu" "In10.Cu"
			)
			(hatch none 0.5)
			(connect_pads
				(clearance 0)
			)
			(min_thickness 0.25)
			(keepout
				(tracks not_allowed)
				(vias allowed)
				(pads allowed)
				(copperpour not_allowed)
				(footprints allowed)
			)
			(placement
				(enabled no)
				(sheetname "")
			)
			(fill
				(thermal_gap 0.5)
				(thermal_bridge_width 0.5)
				(island_removal_mode 0)
			)
			(polygon
				(pts
					(arc
						(start 100.9396 20.884388)
						(mid 99.0854 20.884388)
						(end 100.9396 20.884388)
					)
				)
			)
		)
		(zone
			(layers "F.Cu" "B.Cu" "In1.Cu" "In2.Cu" "In3.Cu" "In4.Cu" "In5.Cu" "In6.Cu"
				"In7.Cu" "In8.Cu" "In9.Cu" "In10.Cu"
			)
			(hatch none 0.5)
			(connect_pads
				(clearance 0)
			)
			(min_thickness 0.25)
			(keepout
				(tracks not_allowed)
				(vias allowed)
				(pads allowed)
				(copperpour not_allowed)
				(footprints allowed)
			)
			(placement
				(enabled no)
				(sheetname "")
			)
			(fill
				(thermal_gap 0.5)
				(thermal_bridge_width 0.5)
				(island_removal_mode 0)
			)
			(polygon
				(pts
					(arc
						(start 103.4796 14.534388)
						(mid 101.6254 14.534388)
						(end 103.4796 14.534388)
					)
				)
			)
		)
		(zone
			(layers "F.Cu" "B.Cu" "In1.Cu" "In2.Cu" "In3.Cu" "In4.Cu" "In5.Cu" "In6.Cu"
				"In7.Cu" "In8.Cu" "In9.Cu" "In10.Cu"
			)
			(hatch none 0.5)
			(connect_pads
				(clearance 0)
			)
			(min_thickness 0.25)
			(keepout
				(tracks not_allowed)
				(vias allowed)
				(pads allowed)
				(copperpour not_allowed)
				(footprints allowed)
			)
			(placement
				(enabled no)
				(sheetname "")
			)
			(fill
				(thermal_gap 0.5)
				(thermal_bridge_width 0.5)
				(island_removal_mode 0)
			)
			(polygon
				(pts
					(arc
						(start 103.4796 20.884388)
						(mid 101.6254 20.884388)
						(end 103.4796 20.884388)
					)
				)
			)
		)
		(zone
			(layer "B.Cu")
			(hatch none 0.5)
			(connect_pads
				(clearance 0)
			)
			(min_thickness 0.25)
			(keepout
				(tracks not_allowed)
				(vias allowed)
				(pads allowed)
				(copperpour not_allowed)
				(footprints allowed)
			)
			(placement
				(enabled no)
				(sheetname "")
			)
			(fill
				(thermal_gap 0.5)
				(thermal_bridge_width 0.5)
				(island_removal_mode 0)
			)
			(polygon
				(pts
					(xy 101.83114 16.883888) (xy 101.735636 16.883888) (xy 101.735636 17.480788) (xy 101.329236 17.480788)
					(xy 101.329236 16.883888) (xy 101.235764 16.883888) (xy 101.235764 17.480788) (xy 100.829364 17.480788)
					(xy 100.829364 16.883888) (xy 100.73386 16.883888) (xy 100.73386 17.582388) (xy 101.83114 17.582388)
				)
			)
		)
	)
)
